# SCM (Grand Teton) — schematic netlist excerpt (pin names and nets, part order shuffled) for the footprints in the layout excerpt that follows; sources: Cadence DE-HDL packaged netlist, KiCad conversion of 12092022_DA0F0TMDCD0_F0T_Management_Board_D_brd_V3_OCP.brd

U10  NCP380HSNAJAAT1G  IC  pkg TSOP6XE  page 28
  \in\  = P5V_AUX
  GND  = GND
  EN  = USB_OC0_EN
  FLAG_N  = USB_OC0_REAR_N
  ILIM  = USB_OC0_ILIM
  \out\  = P5V_USB_REAR

C171  Q_CAP  22UF 10V 20% X6S  pkg C0805  page 28 : A = P5V_AUX ; B = GND

(kicad_pcb
	(version 20260206)
	(generator "pcbnew")
	(generator_version "10.0")
	(general
		(thickness 1.6)
		(legacy_teardrops no)
	)
	(paper "A4")
	(title_block
		(title "12092022_DA0F0TMDCD0_F0T_Management_Board_D_brd_V3_OCP.brd")
		(comment 1 "Grand Teton / footprints 376-377 of 1440")
	)
	(layers
		(0 "F.Cu" signal "TOP")
		(4 "In1.Cu" signal "GND")
		(6 "In2.Cu" signal "IN1")
		(8 "In3.Cu" signal "GND1")
		(10 "In4.Cu" signal "IN2")
		(12 "In5.Cu" signal "VCC")
		(14 "In6.Cu" signal "VCC1")
		(16 "In7.Cu" signal "IN3")
		(18 "In8.Cu" signal "GND2")
		(20 "In9.Cu" signal "IN4")
		(22 "In10.Cu" signal "GND3")
		(2 "B.Cu" signal "BOTTOM")
		(9 "F.Adhes" user "F.Adhesive")
		(11 "B.Adhes" user "B.Adhesive")
		(13 "F.Paste" user "Package Geometry/Pastemask Top")
		(15 "B.Paste" user "Package Geometry/Pastemask Bottom")
		(5 "F.SilkS" user "Ref Des/Silkscreen Top")
		(7 "B.SilkS" user "Ref Des/Silkscreen Bottom")
		(1 "F.Mask" user "Board Geometry/Soldermask Top")
		(3 "B.Mask" user "Board Geometry/Soldermask Bottom")
		(17 "Dwgs.User" user "User.Drawings")
		(19 "Cmts.User" user "User.Comments")
		(21 "Eco1.User" user "User.Eco1")
		(23 "Eco2.User" user "User.Eco2")
		(25 "Edge.Cuts" user "Board Geometry/Outline")
		(27 "Margin" user)
		(31 "F.CrtYd" user "Package Geometry/Place Bound Top")
		(29 "B.CrtYd" user "Package Geometry/Place Bound Bottom")
		(35 "F.Fab" user "Ref Des/Assembly Top")
		(33 "B.Fab" user "Ref Des/Assembly Bottom")
	)
	(footprint ""
		(layer "F.Cu")
		(at 51.19116 -23.450804 180)
		(property "Reference" "U10"
			(at 1.97866 2.138426 0)
			(unlocked yes)
			(layer "F.SilkS")
			(effects
				(font
					(size 0.7874 0.5842)
					(thickness 0.1524)
				)
				(justify left)
			)
		)
		(property "Value" ""
			(at 0 0 180)
			(layer "F.Fab")
			(effects
				(font
					(size 1.27 1.27)
				)
			)
		)
		(duplicate_pad_numbers_are_jumpers no)
		(fp_line
			(start 1.738884 1.549908)
			(end 1.738884 -1.549908)
			(stroke
				(width 0.1524)
				(type default)
			)
			(layer "F.SilkS")
		)
		(fp_line
			(start 1.738884 -1.549908)
			(end 0.635508 -1.549908)
			(stroke
				(width 0.1524)
				(type default)
			)
			(layer "F.SilkS")
		)
		(fp_line
			(start 0.635508 -1.549908)
			(end 0 -0.9144)
			(stroke
				(width 0.1524)
				(type default)
			)
			(layer "F.SilkS")
		)
		(fp_line
			(start 0 -0.9144)
			(end -0.635508 -1.549908)
			(stroke
				(width 0.1524)
				(type default)
			)
			(layer "F.SilkS")
		)
		(fp_line
			(start -0.635508 -1.549908)
			(end -1.738884 -1.549908)
			(stroke
				(width 0.1524)
				(type default)
			)
			(layer "F.SilkS")
		)
		(fp_line
			(start -1.738884 1.549908)
			(end 1.738884 1.549908)
			(stroke
				(width 0.1524)
				(type default)
			)
			(layer "F.SilkS")
		)
		(fp_line
			(start -1.738884 -1.549908)
			(end -1.738884 1.549908)
			(stroke
				(width 0.1524)
				(type default)
			)
			(layer "F.SilkS")
		)
		(fp_poly
			(pts
				(xy -2.445766 -1.211326) (xy -1.923034 -0.94996) (xy -2.445766 -0.688594)
			)
			(stroke
				(width 0)
				(type default)
			)
			(fill yes)
			(layer "F.SilkS")
		)
		(fp_line
			(start 0.849884 1.549908)
			(end 0.849884 -1.549908)
			(stroke
				(width 0.1)
				(type default)
			)
			(layer "F.Fab")
		)
		(fp_line
			(start 0.849884 -1.549908)
			(end -0.849884 -1.549908)
			(stroke
				(width 0.1)
				(type default)
			)
			(layer "F.Fab")
		)
		(fp_line
			(start -0.849884 1.549908)
			(end 0.849884 1.549908)
			(stroke
				(width 0.1)
				(type default)
			)
			(layer "F.Fab")
		)
		(fp_line
			(start -0.849884 -1.549908)
			(end -0.849884 1.549908)
			(stroke
				(width 0.1)
				(type default)
			)
			(layer "F.Fab")
		)
		(fp_poly
			(pts
				(xy -2.445766 -1.211326) (xy -1.923034 -0.94996) (xy -2.445766 -0.688594)
			)
			(stroke
				(width 0)
				(type default)
			)
			(fill yes)
			(layer "F.Fab")
		)
		(pad "1" smd rect
			(at -1.124966 -0.94996 270)
			(size 0.6096 0.9652)
			(layers "F.Cu" "F.Mask" "F.Paste")
			(net "P5V_AUX")
		)
		(pad "2" smd rect
			(at -1.124966 0 270)
			(size 0.6096 0.9652)
			(layers "F.Cu" "F.Mask" "F.Paste")
			(net "GND")
		)
		(pad "3" smd rect
			(at -1.124966 0.94996 270)
			(size 0.6096 0.9652)
			(layers "F.Cu" "F.Mask" "F.Paste")
			(net "USB_OC0_EN")
		)
		(pad "4" smd rect
			(at 1.124966 0.94996 270)
			(size 0.6096 0.9652)
			(layers "F.Cu" "F.Mask" "F.Paste")
			(net "USB_OC0_REAR_N")
		)
		(pad "5" smd rect
			(at 1.124966 0 270)
			(size 0.6096 0.9652)
			(layers "F.Cu" "F.Mask" "F.Paste")
			(net "USB_OC0_ILIM")
		)
		(pad "6" smd rect
			(at 1.124966 -0.94996 270)
			(size 0.6096 0.9652)
			(layers "F.Cu" "F.Mask" "F.Paste")
			(net "P5V_USB_REAR")
		)
	)
	(footprint ""
		(layer "F.Cu")
		(at 55.9054 -21.4884 -90)
		(property "Reference" "C171"
			(at 0 0 270)
			(layer "F.SilkS")
			(hide yes)
			(effects
				(font
					(size 1.27 1.27)
				)
			)
		)
		(property "Value" ""
			(at 0 0 270)
			(layer "F.Fab")
			(effects
				(font
					(size 1.27 1.27)
				)
			)
		)
		(duplicate_pad_numbers_are_jumpers no)
		(fp_line
			(start -1.651 0.8382)
			(end -1.651 -0.8382)
			(stroke
				(width 0.1524)
				(type default)
			)
			(layer "F.SilkS")
		)
		(fp_line
			(start 0 0.8382)
			(end 0 -0.8382)
			(stroke
				(width 0.1524)
				(type default)
			)
			(layer "F.SilkS")
		)
		(fp_line
			(start 1.651 0.8382)
			(end -1.651 0.8382)
			(stroke
				(width 0.1524)
				(type default)
			)
			(layer "F.SilkS")
		)
		(fp_line
			(start -1.651 -0.8382)
			(end 1.651 -0.8382)
			(stroke
				(width 0.1524)
				(type default)
			)
			(layer "F.SilkS")
		)
		(fp_line
			(start 1.651 -0.8382)
			(end 1.651 0.8382)
			(stroke
				(width 0.1524)
				(type default)
			)
			(layer "F.SilkS")
		)
		(fp_line
			(start -1.55956 0.7366)
			(end -1.524 0.7366)
			(stroke
				(width 0.1)
				(type default)
			)
			(layer "F.Fab")
		)
		(fp_line
			(start -1.524 0.7366)
			(end 1.524 0.7366)
			(stroke
				(width 0.1)
				(type default)
			)
			(layer "F.Fab")
		)
		(fp_line
			(start 1.524 0.7366)
			(end 1.55956 0.7366)
			(stroke
				(width 0.1)
				(type default)
			)
			(layer "F.Fab")
		)
		(fp_line
			(start 1.55956 0.7366)
			(end 1.55956 -0.7366)
			(stroke
				(width 0.1)
				(type default)
			)
			(layer "F.Fab")
		)
		(fp_line
			(start -1.55956 -0.7366)
			(end -1.55956 0.7366)
			(stroke
				(width 0.1)
				(type default)
			)
			(layer "F.Fab")
		)
		(fp_line
			(start -1.524 -0.7366)
			(end -1.55956 -0.7366)
			(stroke
				(width 0.1)
				(type default)
			)
			(layer "F.Fab")
		)
		(fp_line
			(start 1.524 -0.7366)
			(end -1.524 -0.7366)
			(stroke
				(width 0.1)
				(type default)
			)
			(layer "F.Fab")
		)
		(fp_line
			(start 1.55956 -0.7366)
			(end 1.524 -0.7366)
			(stroke
				(width 0.1)
				(type default)
			)
			(layer "F.Fab")
		)
		(pad "1" smd rect
			(at -0.94996 0 90)
			(size 1.1176 1.3716)
			(layers "F.Cu" "F.Mask" "F.Paste")
			(net "P5V_AUX")
		)
		(pad "2" smd rect
			(at 0.94996 0 90)
			(size 1.1176 1.3716)
			(layers "F.Cu" "F.Mask" "F.Paste")
			(net "GND")
		)
	)
)
